# S9S_MB_2U (Grand Teton) — schematic netlist excerpt (pin names and nets, part order shuffled) for the footprints in the layout excerpt that follows; sources: Cadence DE-HDL packaged netlist, KiCad conversion of 03242023_DA0F0TMBIJ0_F0T_Motherboard_J_brd_V01_OCP.brd

C820  Q_CAP_DIFFBUS  DIFF BUS_0.22UF 6.3V 20% X6S  pkg C0201  page 175 : \1\ = P5E_CPU1_PE1_TX_C_DN<8> ; \2\ = P5E_CPU1_PE1_TX_DN<8>
PL121  Q_INDUCTOR  4.7UH IND  pkg SMLF  page 300 : \1\ = SW_PVNN_MAIN_CPU1_SW ; \2\ = PVNN_MAIN_CPU1
R717  Q_RES  10K 1% EMPTY  pkg 0402LF  page 243 : A = P3V3_AUX ; B = MB_FRU_ADDR1

(kicad_pcb
	(version 20260206)
	(generator "pcbnew")
	(generator_version "10.0")
	(general
		(thickness 1.6)
		(legacy_teardrops no)
	)
	(paper "A4")
	(title_block
		(title "03242023_DA0F0TMBIJ0_F0T_Motherboard_J_brd_V01_OCP.brd")
		(comment 1 "Grand Teton / footprints 2068-2070 of 6105")
	)
	(layers
		(0 "F.Cu" signal "TOP")
		(4 "In1.Cu" signal "GND")
		(6 "In2.Cu" signal "IN1")
		(8 "In3.Cu" signal "GND1")
		(10 "In4.Cu" signal "IN2")
		(12 "In5.Cu" signal "GND2")
		(14 "In6.Cu" signal "IN3")
		(16 "In7.Cu" signal "GND3")
		(18 "In8.Cu" signal "VCC")
		(20 "In9.Cu" signal "VCC1")
		(22 "In10.Cu" signal "GND4")
		(24 "In11.Cu" signal "IN4")
		(26 "In12.Cu" signal "GND5")
		(28 "In13.Cu" signal "IN5")
		(30 "In14.Cu" signal "GND6")
		(32 "In15.Cu" signal "IN6")
		(34 "In16.Cu" signal "GND7")
		(2 "B.Cu" signal "BOTTOM")
		(9 "F.Adhes" user "F.Adhesive")
		(11 "B.Adhes" user "B.Adhesive")
		(13 "F.Paste" user "Package Geometry/Pastemask Top")
		(15 "B.Paste" user "Package Geometry/Pastemask Bottom")
		(5 "F.SilkS" user "Ref Des/Silkscreen Top")
		(7 "B.SilkS" user "Ref Des/Silkscreen Bottom")
		(1 "F.Mask" user "Board Geometry/Soldermask Top")
		(3 "B.Mask" user "Board Geometry/Soldermask Bottom")
		(17 "Dwgs.User" user "User.Drawings")
		(19 "Cmts.User" user "User.Comments")
		(21 "Eco1.User" user "User.Eco1")
		(23 "Eco2.User" user "User.Eco2")
		(25 "Edge.Cuts" user "Board Geometry/Outline")
		(27 "Margin" user)
		(31 "F.CrtYd" user "Package Geometry/Place Bound Top")
		(29 "B.CrtYd" user "Package Geometry/Place Bound Bottom")
		(35 "F.Fab" user "Ref Des/Assembly Top")
		(33 "B.Fab" user "Ref Des/Assembly Bottom")
	)
	(footprint ""
		(layer "F.Cu")
		(at 35.066478 -17.623536 90)
		(property "Reference" "C820"
			(at 0 0 90)
			(layer "F.SilkS")
			(hide yes)
			(effects
				(font
					(size 1.27 1.27)
				)
			)
		)
		(property "Value" ""
			(at 0 0 90)
			(layer "F.Fab")
			(effects
				(font
					(size 1.27 1.27)
				)
			)
		)
		(duplicate_pad_numbers_are_jumpers no)
		(fp_line
			(start 0.299974 -0.150114)
			(end 0.299974 0.150114)
			(stroke
				(width 0.1)
				(type default)
			)
			(layer "F.Fab")
		)
		(fp_line
			(start -0.299974 -0.150114)
			(end 0.299974 -0.150114)
			(stroke
				(width 0.1)
				(type default)
			)
			(layer "F.Fab")
		)
		(fp_line
			(start 0.299974 0.150114)
			(end -0.299974 0.150114)
			(stroke
				(width 0.1)
				(type default)
			)
			(layer "F.Fab")
		)
		(fp_line
			(start -0.299974 0.150114)
			(end -0.299974 -0.150114)
			(stroke
				(width 0.1)
				(type default)
			)
			(layer "F.Fab")
		)
		(pad "1" smd rect
			(at -0.2667 0 90)
			(size 0.3048 0.381)
			(layers "F.Cu" "F.Mask" "F.Paste")
			(net "P5E_CPU1_PE1_TX_C_DN<8>")
		)
		(pad "2" smd rect
			(at 0.2667 0 90)
			(size 0.3048 0.381)
			(layers "F.Cu" "F.Mask" "F.Paste")
			(net "P5E_CPU1_PE1_TX_DN<8>")
		)
	)
	(footprint ""
		(layer "F.Cu")
		(at 277.6347 -95.029274)
		(property "Reference" "R717"
			(at 0 0 0)
			(layer "F.SilkS")
			(hide yes)
			(effects
				(font
					(size 1.27 1.27)
				)
			)
		)
		(property "Value" ""
			(at 0 0 0)
			(layer "F.Fab")
			(effects
				(font
					(size 1.27 1.27)
				)
			)
		)
		(duplicate_pad_numbers_are_jumpers no)
		(fp_line
			(start -0.7874 -0.4064)
			(end 0.7874 -0.4064)
			(stroke
				(width 0.1524)
				(type default)
			)
			(layer "F.SilkS")
		)
		(fp_line
			(start -0.7874 0.4064)
			(end -0.7874 -0.4064)
			(stroke
				(width 0.1524)
				(type default)
			)
			(layer "F.SilkS")
		)
		(fp_line
			(start 0.7874 -0.4064)
			(end 0.7874 0.4064)
			(stroke
				(width 0.1524)
				(type default)
			)
			(layer "F.SilkS")
		)
		(fp_line
			(start 0.7874 0.4064)
			(end -0.7874 0.4064)
			(stroke
				(width 0.1524)
				(type default)
			)
			(layer "F.SilkS")
		)
		(fp_line
			(start -0.67945 -0.305054)
			(end -0.12065 -0.305054)
			(stroke
				(width 0.1)
				(type default)
			)
			(layer "F.Fab")
		)
		(fp_line
			(start -0.67945 0.3048)
			(end -0.67945 -0.305054)
			(stroke
				(width 0.1)
				(type default)
			)
			(layer "F.Fab")
		)
		(fp_line
			(start -0.12065 -0.305054)
			(end -0.12065 -0.2794)
			(stroke
				(width 0.1)
				(type default)
			)
			(layer "F.Fab")
		)
		(fp_line
			(start -0.12065 -0.2794)
			(end 0.12065 -0.2794)
			(stroke
				(width 0.1)
				(type default)
			)
			(layer "F.Fab")
		)
		(fp_line
			(start -0.12065 0.2794)
			(end -0.12065 0.3048)
			(stroke
				(width 0.1)
				(type default)
			)
			(layer "F.Fab")
		)
		(fp_line
			(start -0.12065 0.3048)
			(end -0.67945 0.3048)
			(stroke
				(width 0.1)
				(type default)
			)
			(layer "F.Fab")
		)
		(fp_line
			(start 0.120396 0.2794)
			(end -0.12065 0.2794)
			(stroke
				(width 0.1)
				(type default)
			)
			(layer "F.Fab")
		)
		(fp_line
			(start 0.120396 0.3048)
			(end 0.120396 0.2794)
			(stroke
				(width 0.1)
				(type default)
			)
			(layer "F.Fab")
		)
		(fp_line
			(start 0.12065 -0.3048)
			(end 0.67945 -0.3048)
			(stroke
				(width 0.1)
				(type default)
			)
			(layer "F.Fab")
		)
		(fp_line
			(start 0.12065 -0.2794)
			(end 0.12065 -0.3048)
			(stroke
				(width 0.1)
				(type default)
			)
			(layer "F.Fab")
		)
		(fp_line
			(start 0.67945 -0.3048)
			(end 0.67945 0.3048)
			(stroke
				(width 0.1)
				(type default)
			)
			(layer "F.Fab")
		)
		(fp_line
			(start 0.67945 0.3048)
			(end 0.120396 0.3048)
			(stroke
				(width 0.1)
				(type default)
			)
			(layer "F.Fab")
		)
		(pad "1" smd circle
			(at -0.40005 0)
			(size 0 0)
			(layers "F.Cu" "F.Mask" "F.Paste")
			(net "P3V3_AUX")
		)
		(pad "2" smd circle
			(at 0.40005 0)
			(size 0 0)
			(layers "F.Cu" "F.Mask" "F.Paste")
			(net "MB_FRU_ADDR1")
		)
	)
	(footprint ""
		(layer "F.Cu")
		(at 30.765242 -179.587906)
		(property "Reference" "PL121"
			(at -1.874012 5.29082 0)
			(unlocked yes)
			(layer "F.SilkS")
			(effects
				(font
					(size 0.7874 0.5842)
					(thickness 0.1524)
				)
				(justify left)
			)
		)
		(property "Value" ""
			(at 0 0 0)
			(layer "F.Fab")
			(effects
				(font
					(size 1.27 1.27)
				)
			)
		)
		(duplicate_pad_numbers_are_jumpers no)
		(fp_line
			(start -3.6576 -3.350006)
			(end 3.64998 -3.350006)
			(stroke
				(width 0.1524)
				(type default)
			)
			(layer "F.SilkS")
		)
		(fp_line
			(start -3.64998 -1.8034)
			(end -3.64998 -3.350006)
			(stroke
				(width 0.1524)
				(type default)
			)
			(layer "F.SilkS")
		)
		(fp_line
			(start -3.64998 3.350006)
			(end -3.64998 1.8288)
			(stroke
				(width 0.1524)
				(type default)
			)
			(layer "F.SilkS")
		)
		(fp_line
			(start 3.64998 -3.350006)
			(end 3.64998 -1.8034)
			(stroke
				(width 0.1524)
				(type default)
			)
			(layer "F.SilkS")
		)
		(fp_line
			(start 3.64998 1.8034)
			(end 3.64998 3.350006)
			(stroke
				(width 0.1524)
				(type default)
			)
			(layer "F.SilkS")
		)
		(fp_line
			(start 3.64998 3.350006)
			(end -3.64998 3.350006)
			(stroke
				(width 0.1524)
				(type default)
			)
			(layer "F.SilkS")
		)
		(fp_line
			(start -3.64998 -3.350006)
			(end 3.64998 -3.350006)
			(stroke
				(width 0.1)
				(type default)
			)
			(layer "F.Fab")
		)
		(fp_line
			(start -3.64998 3.350006)
			(end -3.64998 -3.350006)
			(stroke
				(width 0.1)
				(type default)
			)
			(layer "F.Fab")
		)
		(fp_line
			(start 3.64998 -3.350006)
			(end 3.64998 3.350006)
			(stroke
				(width 0.1)
				(type default)
			)
			(layer "F.Fab")
		)
		(fp_line
			(start 3.64998 3.350006)
			(end -3.64998 3.350006)
			(stroke
				(width 0.1)
				(type default)
			)
			(layer "F.Fab")
		)
		(pad "1" smd rect
			(at -2.92481 0)
			(size 2.15392 3.302)
			(layers "F.Cu" "F.Mask" "F.Paste")
			(net "SW_PVNN_MAIN_CPU1_SW")
		)
		(pad "2" smd rect
			(at 2.92481 0)
			(size 2.15392 3.302)
			(layers "F.Cu" "F.Mask" "F.Paste")
			(net "PVNN_MAIN_CPU1")
		)
	)
)
